# S9S_MB_2U (Grand Teton) — schematic netlist excerpt (pin names and nets, part order shuffled) for the footprints in the layout excerpt that follows; sources: Cadence DE-HDL packaged netlist, KiCad conversion of 03242023_DA0F0TMBIJ0_F0T_Motherboard_J_brd_V01_OCP.brd

C1803  Q_CAP  0.1UF 25V 10% X7R  pkg 0402  page 151 : A = P3V3_AUX ; B = GND
R3628  Q_RES  4.7K 1% EMPTY  pkg 0402LF  page 171 : A = P3V3_AUX ; B = INA230_1_A1

(kicad_pcb
	(version 20260206)
	(generator "pcbnew")
	(generator_version "10.0")
	(general
		(thickness 1.6)
		(legacy_teardrops no)
	)
	(paper "A4")
	(title_block
		(title "03242023_DA0F0TMBIJ0_F0T_Motherboard_J_brd_V01_OCP.brd")
		(comment 1 "Grand Teton / footprints 2137-2138 of 6105")
	)
	(layers
		(0 "F.Cu" signal "TOP")
		(4 "In1.Cu" signal "GND")
		(6 "In2.Cu" signal "IN1")
		(8 "In3.Cu" signal "GND1")
		(10 "In4.Cu" signal "IN2")
		(12 "In5.Cu" signal "GND2")
		(14 "In6.Cu" signal "IN3")
		(16 "In7.Cu" signal "GND3")
		(18 "In8.Cu" signal "VCC")
		(20 "In9.Cu" signal "VCC1")
		(22 "In10.Cu" signal "GND4")
		(24 "In11.Cu" signal "IN4")
		(26 "In12.Cu" signal "GND5")
		(28 "In13.Cu" signal "IN5")
		(30 "In14.Cu" signal "GND6")
		(32 "In15.Cu" signal "IN6")
		(34 "In16.Cu" signal "GND7")
		(2 "B.Cu" signal "BOTTOM")
		(9 "F.Adhes" user "F.Adhesive")
		(11 "B.Adhes" user "B.Adhesive")
		(13 "F.Paste" user "Package Geometry/Pastemask Top")
		(15 "B.Paste" user "Package Geometry/Pastemask Bottom")
		(5 "F.SilkS" user "Ref Des/Silkscreen Top")
		(7 "B.SilkS" user "Ref Des/Silkscreen Bottom")
		(1 "F.Mask" user "Board Geometry/Soldermask Top")
		(3 "B.Mask" user "Board Geometry/Soldermask Bottom")
		(17 "Dwgs.User" user "User.Drawings")
		(19 "Cmts.User" user "User.Comments")
		(21 "Eco1.User" user "User.Eco1")
		(23 "Eco2.User" user "User.Eco2")
		(25 "Edge.Cuts" user "Board Geometry/Outline")
		(27 "Margin" user)
		(31 "F.CrtYd" user "Package Geometry/Place Bound Top")
		(29 "B.CrtYd" user "Package Geometry/Place Bound Bottom")
		(35 "F.Fab" user "Ref Des/Assembly Top")
		(33 "B.Fab" user "Ref Des/Assembly Bottom")
	)
	(footprint ""
		(layer "F.Cu")
		(at 445.157098 -92.468192 180)
		(property "Reference" "R3628"
			(at 0 0 180)
			(layer "F.SilkS")
			(hide yes)
			(effects
				(font
					(size 1.27 1.27)
				)
			)
		)
		(property "Value" ""
			(at 0 0 180)
			(layer "F.Fab")
			(effects
				(font
					(size 1.27 1.27)
				)
			)
		)
		(duplicate_pad_numbers_are_jumpers no)
		(fp_line
			(start 0.7874 0.4064)
			(end -0.7874 0.4064)
			(stroke
				(width 0.1524)
				(type default)
			)
			(layer "F.SilkS")
		)
		(fp_line
			(start 0.7874 -0.4064)
			(end 0.7874 0.4064)
			(stroke
				(width 0.1524)
				(type default)
			)
			(layer "F.SilkS")
		)
		(fp_line
			(start -0.7874 0.4064)
			(end -0.7874 -0.4064)
			(stroke
				(width 0.1524)
				(type default)
			)
			(layer "F.SilkS")
		)
		(fp_line
			(start -0.7874 -0.4064)
			(end 0.7874 -0.4064)
			(stroke
				(width 0.1524)
				(type default)
			)
			(layer "F.SilkS")
		)
		(fp_line
			(start 0.67945 0.3048)
			(end 0.120396 0.3048)
			(stroke
				(width 0.1)
				(type default)
			)
			(layer "F.Fab")
		)
		(fp_line
			(start 0.67945 -0.3048)
			(end 0.67945 0.3048)
			(stroke
				(width 0.1)
				(type default)
			)
			(layer "F.Fab")
		)
		(fp_line
			(start 0.12065 -0.2794)
			(end 0.12065 -0.3048)
			(stroke
				(width 0.1)
				(type default)
			)
			(layer "F.Fab")
		)
		(fp_line
			(start 0.12065 -0.3048)
			(end 0.67945 -0.3048)
			(stroke
				(width 0.1)
				(type default)
			)
			(layer "F.Fab")
		)
		(fp_line
			(start 0.120396 0.3048)
			(end 0.120396 0.2794)
			(stroke
				(width 0.1)
				(type default)
			)
			(layer "F.Fab")
		)
		(fp_line
			(start 0.120396 0.2794)
			(end -0.12065 0.2794)
			(stroke
				(width 0.1)
				(type default)
			)
			(layer "F.Fab")
		)
		(fp_line
			(start -0.12065 0.3048)
			(end -0.67945 0.3048)
			(stroke
				(width 0.1)
				(type default)
			)
			(layer "F.Fab")
		)
		(fp_line
			(start -0.12065 0.2794)
			(end -0.12065 0.3048)
			(stroke
				(width 0.1)
				(type default)
			)
			(layer "F.Fab")
		)
		(fp_line
			(start -0.12065 -0.2794)
			(end 0.12065 -0.2794)
			(stroke
				(width 0.1)
				(type default)
			)
			(layer "F.Fab")
		)
		(fp_line
			(start -0.12065 -0.305054)
			(end -0.12065 -0.2794)
			(stroke
				(width 0.1)
				(type default)
			)
			(layer "F.Fab")
		)
		(fp_line
			(start -0.67945 0.3048)
			(end -0.67945 -0.305054)
			(stroke
				(width 0.1)
				(type default)
			)
			(layer "F.Fab")
		)
		(fp_line
			(start -0.67945 -0.305054)
			(end -0.12065 -0.305054)
			(stroke
				(width 0.1)
				(type default)
			)
			(layer "F.Fab")
		)
		(pad "1" smd circle
			(at -0.40005 0 180)
			(size 0 0)
			(layers "F.Cu" "F.Mask" "F.Paste")
			(net "P3V3_AUX")
		)
		(pad "2" smd circle
			(at 0.40005 0 180)
			(size 0 0)
			(layers "F.Cu" "F.Mask" "F.Paste")
			(net "INA230_1_A1")
		)
	)
	(footprint ""
		(layer "F.Cu")
		(at 366.18672 -403.957028)
		(property "Reference" "C1803"
			(at 0 0 0)
			(layer "F.SilkS")
			(hide yes)
			(effects
				(font
					(size 1.27 1.27)
				)
			)
		)
		(property "Value" ""
			(at 0 0 0)
			(layer "F.Fab")
			(effects
				(font
					(size 1.27 1.27)
				)
			)
		)
		(duplicate_pad_numbers_are_jumpers no)
		(fp_line
			(start -0.7874 -0.4064)
			(end 0.7874 -0.4064)
			(stroke
				(width 0.1524)
				(type default)
			)
			(layer "F.SilkS")
		)
		(fp_line
			(start -0.7874 0.4064)
			(end -0.7874 -0.4064)
			(stroke
				(width 0.1524)
				(type default)
			)
			(layer "F.SilkS")
		)
		(fp_line
			(start 0.7874 -0.4064)
			(end 0.7874 0.4064)
			(stroke
				(width 0.1524)
				(type default)
			)
			(layer "F.SilkS")
		)
		(fp_line
			(start 0.7874 0.4064)
			(end -0.7874 0.4064)
			(stroke
				(width 0.1524)
				(type default)
			)
			(layer "F.SilkS")
		)
		(fp_line
			(start -0.67945 -0.305054)
			(end -0.12065 -0.305054)
			(stroke
				(width 0.1)
				(type default)
			)
			(layer "F.Fab")
		)
		(fp_line
			(start -0.67945 0.3048)
			(end -0.67945 -0.305054)
			(stroke
				(width 0.1)
				(type default)
			)
			(layer "F.Fab")
		)
		(fp_line
			(start -0.12065 -0.305054)
			(end -0.12065 -0.2794)
			(stroke
				(width 0.1)
				(type default)
			)
			(layer "F.Fab")
		)
		(fp_line
			(start -0.12065 -0.2794)
			(end 0.12065 -0.2794)
			(stroke
				(width 0.1)
				(type default)
			)
			(layer "F.Fab")
		)
		(fp_line
			(start -0.12065 0.2794)
			(end -0.12065 0.3048)
			(stroke
				(width 0.1)
				(type default)
			)
			(layer "F.Fab")
		)
		(fp_line
			(start -0.12065 0.3048)
			(end -0.67945 0.3048)
			(stroke
				(width 0.1)
				(type default)
			)
			(layer "F.Fab")
		)
		(fp_line
			(start 0.120396 0.2794)
			(end -0.12065 0.2794)
			(stroke
				(width 0.1)
				(type default)
			)
			(layer "F.Fab")
		)
		(fp_line
			(start 0.120396 0.3048)
			(end 0.120396 0.2794)
			(stroke
				(width 0.1)
				(type default)
			)
			(layer "F.Fab")
		)
		(fp_line
			(start 0.12065 -0.3048)
			(end 0.67945 -0.3048)
			(stroke
				(width 0.1)
				(type default)
			)
			(layer "F.Fab")
		)
		(fp_line
			(start 0.12065 -0.2794)
			(end 0.12065 -0.3048)
			(stroke
				(width 0.1)
				(type default)
			)
			(layer "F.Fab")
		)
		(fp_line
			(start 0.67945 -0.3048)
			(end 0.67945 0.3048)
			(stroke
				(width 0.1)
				(type default)
			)
			(layer "F.Fab")
		)
		(fp_line
			(start 0.67945 0.3048)
			(end 0.120396 0.3048)
			(stroke
				(width 0.1)
				(type default)
			)
			(layer "F.Fab")
		)
		(pad "1" smd circle
			(at -0.40005 0)
			(size 0 0)
			(layers "F.Cu" "F.Mask" "F.Paste")
			(net "P3V3_AUX")
		)
		(pad "2" smd circle
			(at 0.40005 0)
			(size 0 0)
			(layers "F.Cu" "F.Mask" "F.Paste")
			(net "GND")
		)
	)
)
